(kicad_pcb
	(version 20260206)
	(generator "pcbnew")
	(generator_version "10.0")
	(general
		(thickness 1.6)
		(legacy_teardrops no)
	)
	(paper "A4")
	(title_block
		(title "v1-tray-backplane — T6M_tray_BP_c_1023_1120.brd")
		(comment 1 "Open CloudServer (Microsoft) / footprint 149 of 170 (J8), pads 1-54 of 54")
	)
	(layers
		(0 "F.Cu" signal "TOP")
		(4 "In1.Cu" signal "GND")
		(6 "In2.Cu" signal "IN1")
		(8 "In3.Cu" signal "VCC")
		(10 "In4.Cu" signal "VCC1")
		(12 "In5.Cu" signal "IN2")
		(14 "In6.Cu" signal "GND1")
		(2 "B.Cu" signal "BOTTOM")
		(9 "F.Adhes" user "F.Adhesive")
		(11 "B.Adhes" user "B.Adhesive")
		(13 "F.Paste" user "Package Geometry/Pastemask Top")
		(15 "B.Paste" user "Package Geometry/Pastemask Bottom")
		(5 "F.SilkS" user "Ref Des/Silkscreen Top")
		(7 "B.SilkS" user "Ref Des/Silkscreen Bottom")
		(1 "F.Mask" user "Board Geometry/Soldermask Top")
		(3 "B.Mask" user "Board Geometry/Soldermask Bottom")
		(17 "Dwgs.User" user "User.Drawings")
		(19 "Cmts.User" user "User.Comments")
		(21 "Eco1.User" user "User.Eco1")
		(23 "Eco2.User" user "User.Eco2")
		(25 "Edge.Cuts" user "Board Geometry/Outline")
		(27 "Margin" user)
		(31 "F.CrtYd" user "Package Geometry/Place Bound Top")
		(29 "B.CrtYd" user "Package Geometry/Place Bound Bottom")
		(35 "F.Fab" user "Ref Des/Assembly Top")
		(33 "B.Fab" user "Ref Des/Assembly Bottom")
	)
	(footprint ""
		(layer "F.Cu")
		(at 395.889988 -2.100072 180)
		(property "Reference" "J8"
			(at -4.872736 -0.63246 90)
			(unlocked yes)
			(layer "F.SilkS")
			(effects
				(font
					(size 0.7874 0.5842)
					(thickness 0.1524)
				)
				(justify left)
			)
		)
		(property "Value" ""
			(at 0 0 180)
			(layer "F.Fab")
			(effects
				(font
					(size 1.27 1.27)
				)
			)
		)
		(duplicate_pad_numbers_are_jumpers no)
		(pad "A1" thru_hole rect
			(at 0 0)
			(size 0.9144 0.9144)
			(drill 0.508)
			(layers "*.Cu" "*.Mask")
			(remove_unused_layers no)
			(net "SAS_BLAD2_TX1_P")
			(clearance 0.0508)
			(thermal_gap 0.0508)
			(padstack
				(mode front_inner_back)
				(layer "Inner"
					(shape circle)
					(size 0.9144 0.9144)
					(clearance 0.0508)
				)
				(layer "B.Cu"
					(shape rect)
					(size 0.9144 0.9144)
					(clearance 0.0508)
				)
			)
		)
		(pad "A2" thru_hole circle
			(at 1.999996 -0.100076)
			(size 0.9144 0.9144)
			(drill 0.508)
			(layers "*.Cu" "*.Mask")
			(remove_unused_layers no)
			(net "GND")
			(clearance 0.0508)
			(thermal_gap 0.0508)
		)
		(pad "A3" thru_hole circle
			(at 3.999992 0)
			(size 0.9144 0.9144)
			(drill 0.508)
			(layers "*.Cu" "*.Mask")
			(remove_unused_layers no)
			(net "AIRMAX_RSVD7")
			(clearance 0.0508)
			(thermal_gap 0.0508)
		)
		(pad "A4" thru_hole circle
			(at 5.999988 -0.100076)
			(size 0.9144 0.9144)
			(drill 0.508)
			(layers "*.Cu" "*.Mask")
			(remove_unused_layers no)
			(net "GND")
			(clearance 0.0508)
			(thermal_gap 0.0508)
		)
		(pad "A5" thru_hole circle
			(at 7.999984 0)
			(size 0.9144 0.9144)
			(drill 0.508)
			(layers "*.Cu" "*.Mask")
			(remove_unused_layers no)
			(net "SAS_BLAD2_TX6_P")
			(clearance 0.0508)
			(thermal_gap 0.0508)
		)
		(pad "A6" thru_hole circle
			(at 9.99998 -0.100076)
			(size 0.9144 0.9144)
			(drill 0.508)
			(layers "*.Cu" "*.Mask")
			(remove_unused_layers no)
			(net "GND")
			(clearance 0.0508)
			(thermal_gap 0.0508)
		)
		(pad "B1" thru_hole circle
			(at 0 1.400048)
			(size 0.9144 0.9144)
			(drill 0.508)
			(layers "*.Cu" "*.Mask")
			(remove_unused_layers no)
			(net "SAS_BLAD2_TX1_N")
			(clearance 0.0508)
			(thermal_gap 0.0508)
		)
		(pad "B2" thru_hole circle
			(at 1.999996 1.299972)
			(size 0.9144 0.9144)
			(drill 0.508)
			(layers "*.Cu" "*.Mask")
			(remove_unused_layers no)
			(net "SAS_BLAD2_RX3_P")
			(clearance 0.0508)
			(thermal_gap 0.0508)
		)
		(pad "B3" thru_hole circle
			(at 3.999992 1.400048)
			(size 0.9144 0.9144)
			(drill 0.508)
			(layers "*.Cu" "*.Mask")
			(remove_unused_layers no)
			(net "AIRMAX_RSVD8")
			(clearance 0.0508)
			(thermal_gap 0.0508)
		)
		(pad "B4" thru_hole circle
			(at 5.999988 1.299972)
			(size 0.9144 0.9144)
			(drill 0.508)
			(layers "*.Cu" "*.Mask")
			(remove_unused_layers no)
			(net "AIRMAX_RSVD5")
			(clearance 0.0508)
			(thermal_gap 0.0508)
		)
		(pad "B5" thru_hole circle
			(at 7.999984 1.400048)
			(size 0.9144 0.9144)
			(drill 0.508)
			(layers "*.Cu" "*.Mask")
			(remove_unused_layers no)
			(net "SAS_BLAD2_TX6_N")
			(clearance 0.0508)
			(thermal_gap 0.0508)
		)
		(pad "B6" thru_hole circle
			(at 9.99998 1.299972)
			(size 0.9144 0.9144)
			(drill 0.508)
			(layers "*.Cu" "*.Mask")
			(remove_unused_layers no)
			(net "SAS_BLAD2_RX8_P")
			(clearance 0.0508)
			(thermal_gap 0.0508)
		)
		(pad "C1" thru_hole circle
			(at 0 2.800096)
			(size 0.9144 0.9144)
			(drill 0.508)
			(layers "*.Cu" "*.Mask")
			(remove_unused_layers no)
			(net "GND")
			(clearance 0.0508)
			(thermal_gap 0.0508)
		)
		(pad "C2" thru_hole circle
			(at 1.999996 2.70002)
			(size 0.9144 0.9144)
			(drill 0.508)
			(layers "*.Cu" "*.Mask")
			(remove_unused_layers no)
			(net "SAS_BLAD2_RX3_N")
			(clearance 0.0508)
			(thermal_gap 0.0508)
		)
		(pad "C3" thru_hole circle
			(at 3.999992 2.800096)
			(size 0.9144 0.9144)
			(drill 0.508)
			(layers "*.Cu" "*.Mask")
			(remove_unused_layers no)
			(net "GND")
			(clearance 0.0508)
			(thermal_gap 0.0508)
		)
		(pad "C4" thru_hole circle
			(at 5.999988 2.70002)
			(size 0.9144 0.9144)
			(drill 0.508)
			(layers "*.Cu" "*.Mask")
			(remove_unused_layers no)
			(net "AIRMAX_RSVD6")
			(clearance 0.0508)
			(thermal_gap 0.0508)
		)
		(pad "C5" thru_hole circle
			(at 7.999984 2.800096)
			(size 0.9144 0.9144)
			(drill 0.508)
			(layers "*.Cu" "*.Mask")
			(remove_unused_layers no)
			(net "GND")
			(clearance 0.0508)
			(thermal_gap 0.0508)
		)
		(pad "C6" thru_hole circle
			(at 9.99998 2.70002)
			(size 0.9144 0.9144)
			(drill 0.508)
			(layers "*.Cu" "*.Mask")
			(remove_unused_layers no)
			(net "SAS_BLAD2_RX8_N")
			(clearance 0.0508)
			(thermal_gap 0.0508)
		)
		(pad "D1" thru_hole circle
			(at 0 4.19989)
			(size 0.9144 0.9144)
			(drill 0.508)
			(layers "*.Cu" "*.Mask")
			(remove_unused_layers no)
			(net "SAS_BLAD2_RX1_P")
			(clearance 0.0508)
			(thermal_gap 0.0508)
		)
		(pad "D2" thru_hole circle
			(at 1.999996 4.100068)
			(size 0.9144 0.9144)
			(drill 0.508)
			(layers "*.Cu" "*.Mask")
			(remove_unused_layers no)
			(net "GND")
			(clearance 0.0508)
			(thermal_gap 0.0508)
		)
		(pad "D3" thru_hole circle
			(at 3.999992 4.19989)
			(size 0.9144 0.9144)
			(drill 0.508)
			(layers "*.Cu" "*.Mask")
			(remove_unused_layers no)
			(net "SAS_BLAD2_RX4_P")
			(clearance 0.0508)
			(thermal_gap 0.0508)
		)
		(pad "D4" thru_hole circle
			(at 5.999988 4.100068)
			(size 0.9144 0.9144)
			(drill 0.508)
			(layers "*.Cu" "*.Mask")
			(remove_unused_layers no)
			(net "GND")
			(clearance 0.0508)
			(thermal_gap 0.0508)
		)
		(pad "D5" thru_hole circle
			(at 7.999984 4.19989)
			(size 0.9144 0.9144)
			(drill 0.508)
			(layers "*.Cu" "*.Mask")
			(remove_unused_layers no)
			(net "SAS_BLAD2_RX6_P")
			(clearance 0.0508)
			(thermal_gap 0.0508)
		)
		(pad "D6" thru_hole circle
			(at 9.99998 4.100068)
			(size 0.9144 0.9144)
			(drill 0.508)
			(layers "*.Cu" "*.Mask")
			(remove_unused_layers no)
			(net "GND")
			(clearance 0.0508)
			(thermal_gap 0.0508)
		)
		(pad "E1" thru_hole circle
			(at 0 5.599938)
			(size 0.9144 0.9144)
			(drill 0.508)
			(layers "*.Cu" "*.Mask")
			(remove_unused_layers no)
			(net "SAS_BLAD2_RX1_N")
			(clearance 0.0508)
			(thermal_gap 0.0508)
		)
		(pad "E2" thru_hole circle
			(at 1.999996 5.500116)
			(size 0.9144 0.9144)
			(drill 0.508)
			(layers "*.Cu" "*.Mask")
			(remove_unused_layers no)
			(net "SAS_BLAD2_TX3_P")
			(clearance 0.0508)
			(thermal_gap 0.0508)
		)
		(pad "E3" thru_hole circle
			(at 3.999992 5.599938)
			(size 0.9144 0.9144)
			(drill 0.508)
			(layers "*.Cu" "*.Mask")
			(remove_unused_layers no)
			(net "SAS_BLAD2_RX4_N")
			(clearance 0.0508)
			(thermal_gap 0.0508)
		)
		(pad "E4" thru_hole circle
			(at 5.999988 5.500116)
			(size 0.9144 0.9144)
			(drill 0.508)
			(layers "*.Cu" "*.Mask")
			(remove_unused_layers no)
			(net "SAS_BLAD2_TX5_P")
			(clearance 0.0508)
			(thermal_gap 0.0508)
		)
		(pad "E5" thru_hole circle
			(at 7.999984 5.599938)
			(size 0.9144 0.9144)
			(drill 0.508)
			(layers "*.Cu" "*.Mask")
			(remove_unused_layers no)
			(net "SAS_BLAD2_RX6_N")
			(clearance 0.0508)
			(thermal_gap 0.0508)
		)
		(pad "E6" thru_hole circle
			(at 9.99998 5.500116)
			(size 0.9144 0.9144)
			(drill 0.508)
			(layers "*.Cu" "*.Mask")
			(remove_unused_layers no)
			(net "SAS_BLAD2_TX8_P")
			(clearance 0.0508)
			(thermal_gap 0.0508)
		)
		(pad "F1" thru_hole circle
			(at 0 6.999986)
			(size 0.9144 0.9144)
			(drill 0.508)
			(layers "*.Cu" "*.Mask")
			(remove_unused_layers no)
			(net "GND")
			(clearance 0.0508)
			(thermal_gap 0.0508)
		)
		(pad "F2" thru_hole circle
			(at 1.999996 6.89991)
			(size 0.9144 0.9144)
			(drill 0.508)
			(layers "*.Cu" "*.Mask")
			(remove_unused_layers no)
			(net "SAS_BLAD2_TX3_N")
			(clearance 0.0508)
			(thermal_gap 0.0508)
		)
		(pad "F3" thru_hole circle
			(at 3.999992 6.999986)
			(size 0.9144 0.9144)
			(drill 0.508)
			(layers "*.Cu" "*.Mask")
			(remove_unused_layers no)
			(net "GND")
			(clearance 0.0508)
			(thermal_gap 0.0508)
		)
		(pad "F4" thru_hole circle
			(at 5.999988 6.89991)
			(size 0.9144 0.9144)
			(drill 0.508)
			(layers "*.Cu" "*.Mask")
			(remove_unused_layers no)
			(net "SAS_BLAD2_TX5_N")
			(clearance 0.0508)
			(thermal_gap 0.0508)
		)
		(pad "F5" thru_hole circle
			(at 7.999984 6.999986)
			(size 0.9144 0.9144)
			(drill 0.508)
			(layers "*.Cu" "*.Mask")
			(remove_unused_layers no)
			(net "GND")
			(clearance 0.0508)
			(thermal_gap 0.0508)
		)
		(pad "F6" thru_hole circle
			(at 9.99998 6.89991)
			(size 0.9144 0.9144)
			(drill 0.508)
			(layers "*.Cu" "*.Mask")
			(remove_unused_layers no)
			(net "SAS_BLAD2_TX8_N")
			(clearance 0.0508)
			(thermal_gap 0.0508)
		)
		(pad "G1" thru_hole circle
			(at 0 8.400034)
			(size 0.9144 0.9144)
			(drill 0.508)
			(layers "*.Cu" "*.Mask")
			(remove_unused_layers no)
			(net "SAS_BLAD2_TX2_P")
			(clearance 0.0508)
			(thermal_gap 0.0508)
		)
		(pad "G2" thru_hole circle
			(at 1.999996 8.299958)
			(size 0.9144 0.9144)
			(drill 0.508)
			(layers "*.Cu" "*.Mask")
			(remove_unused_layers no)
			(net "GND")
			(clearance 0.0508)
			(thermal_gap 0.0508)
		)
		(pad "G3" thru_hole circle
			(at 3.999992 8.400034)
			(size 0.9144 0.9144)
			(drill 0.508)
			(layers "*.Cu" "*.Mask")
			(remove_unused_layers no)
			(net "SAS_BLAD2_TX4_P")
			(clearance 0.0508)
			(thermal_gap 0.0508)
		)
		(pad "G4" thru_hole circle
			(at 5.999988 8.299958)
			(size 0.9144 0.9144)
			(drill 0.508)
			(layers "*.Cu" "*.Mask")
			(remove_unused_layers no)
			(net "GND")
			(clearance 0.0508)
			(thermal_gap 0.0508)
		)
		(pad "G5" thru_hole circle
			(at 7.999984 8.400034)
			(size 0.9144 0.9144)
			(drill 0.508)
			(layers "*.Cu" "*.Mask")
			(remove_unused_layers no)
			(net "SAS_BLAD2_TX7_P")
			(clearance 0.0508)
			(thermal_gap 0.0508)
		)
		(pad "G6" thru_hole circle
			(at 9.99998 8.299958)
			(size 0.9144 0.9144)
			(drill 0.508)
			(layers "*.Cu" "*.Mask")
			(remove_unused_layers no)
			(net "GND")
			(clearance 0.0508)
			(thermal_gap 0.0508)
		)
		(pad "H1" thru_hole circle
			(at 0 9.800082)
			(size 0.9144 0.9144)
			(drill 0.508)
			(layers "*.Cu" "*.Mask")
			(remove_unused_layers no)
			(net "SAS_BLAD2_TX2_N")
			(clearance 0.0508)
			(thermal_gap 0.0508)
		)
		(pad "H2" thru_hole circle
			(at 1.999996 9.700006)
			(size 0.9144 0.9144)
			(drill 0.508)
			(layers "*.Cu" "*.Mask")
			(remove_unused_layers no)
			(net "SAS_BLAD2_RX2_P")
			(clearance 0.0508)
			(thermal_gap 0.0508)
		)
		(pad "H3" thru_hole circle
			(at 3.999992 9.800082)
			(size 0.9144 0.9144)
			(drill 0.508)
			(layers "*.Cu" "*.Mask")
			(remove_unused_layers no)
			(net "SAS_BLAD2_TX4_N")
			(clearance 0.0508)
			(thermal_gap 0.0508)
		)
		(pad "H4" thru_hole circle
			(at 5.999988 9.700006)
			(size 0.9144 0.9144)
			(drill 0.508)
			(layers "*.Cu" "*.Mask")
			(remove_unused_layers no)
			(net "SAS_BLAD2_RX5_P")
			(clearance 0.0508)
			(thermal_gap 0.0508)
		)
		(pad "H5" thru_hole circle
			(at 7.999984 9.800082)
			(size 0.9144 0.9144)
			(drill 0.508)
			(layers "*.Cu" "*.Mask")
			(remove_unused_layers no)
			(net "SAS_BLAD2_TX7_N")
			(clearance 0.0508)
			(thermal_gap 0.0508)
		)
		(pad "H6" thru_hole circle
			(at 9.99998 9.700006)
			(size 0.9144 0.9144)
			(drill 0.508)
			(layers "*.Cu" "*.Mask")
			(remove_unused_layers no)
			(net "SAS_BLAD2_RX7_P")
			(clearance 0.0508)
			(thermal_gap 0.0508)
		)
		(pad "I1" thru_hole circle
			(at 0 11.199876)
			(size 0.9144 0.9144)
			(drill 0.508)
			(layers "*.Cu" "*.Mask")
			(remove_unused_layers no)
			(net "GND")
			(clearance 0.0508)
			(thermal_gap 0.0508)
		)
		(pad "I2" thru_hole circle
			(at 1.999996 11.100054)
			(size 0.9144 0.9144)
			(drill 0.508)
			(layers "*.Cu" "*.Mask")
			(remove_unused_layers no)
			(net "SAS_BLAD2_RX2_N")
			(clearance 0.0508)
			(thermal_gap 0.0508)
		)
		(pad "I3" thru_hole circle
			(at 3.999992 11.199876)
			(size 0.9144 0.9144)
			(drill 0.508)
			(layers "*.Cu" "*.Mask")
			(remove_unused_layers no)
			(net "GND")
			(clearance 0.0508)
			(thermal_gap 0.0508)
		)
		(pad "I4" thru_hole circle
			(at 5.999988 11.100054)
			(size 0.9144 0.9144)
			(drill 0.508)
			(layers "*.Cu" "*.Mask")
			(remove_unused_layers no)
			(net "SAS_BLAD2_RX5_N")
			(clearance 0.0508)
			(thermal_gap 0.0508)
		)
		(pad "I5" thru_hole circle
			(at 7.999984 11.199876)
			(size 0.9144 0.9144)
			(drill 0.508)
			(layers "*.Cu" "*.Mask")
			(remove_unused_layers no)
			(net "GND")
			(clearance 0.0508)
			(thermal_gap 0.0508)
		)
		(pad "I6" thru_hole circle
			(at 9.99998 11.100054)
			(size 0.9144 0.9144)
			(drill 0.508)
			(layers "*.Cu" "*.Mask")
			(remove_unused_layers no)
			(net "SAS_BLAD2_RX7_N")
			(clearance 0.0508)
			(thermal_gap 0.0508)
		)
	)
)
